# S9S_MB_2U (Grand Teton) — schematic netlist excerpt (pin names and nets, part order shuffled) for the footprints in the layout excerpt that follows; sources: Cadence DE-HDL packaged netlist, KiCad conversion of 03242023_DA0F0TMBIJ0_F0T_Motherboard_J_brd_V01_OCP.brd

R3592  Q_RES  33.2 1% CHIP  pkg 0402LF  page 232 : A = SMB_INA230_3V3AUX_SCL ; B = SMB_INA230_5_3V3AUX_SCL_R

Q153  MOSFET_NCH_DUAL  PJT138K IC  pkg SOT363XD  page 144
  S1  = GND
  G1  = PRSNT_CABLE_SWB_B1_N
  D2  = PRSNT_CABLE_SWB_B1_ISO_N
  S2  = GND
  G2  = PRSNT_CABLE_SWB_B1
  D1  = PRSNT_CABLE_SWB_B1

(kicad_pcb
	(version 20260206)
	(generator "pcbnew")
	(generator_version "10.0")
	(general
		(thickness 1.6)
		(legacy_teardrops no)
	)
	(paper "A4")
	(title_block
		(title "03242023_DA0F0TMBIJ0_F0T_Motherboard_J_brd_V01_OCP.brd")
		(comment 1 "Grand Teton / footprints 579-580 of 6105")
	)
	(layers
		(0 "F.Cu" signal "TOP")
		(4 "In1.Cu" signal "GND")
		(6 "In2.Cu" signal "IN1")
		(8 "In3.Cu" signal "GND1")
		(10 "In4.Cu" signal "IN2")
		(12 "In5.Cu" signal "GND2")
		(14 "In6.Cu" signal "IN3")
		(16 "In7.Cu" signal "GND3")
		(18 "In8.Cu" signal "VCC")
		(20 "In9.Cu" signal "VCC1")
		(22 "In10.Cu" signal "GND4")
		(24 "In11.Cu" signal "IN4")
		(26 "In12.Cu" signal "GND5")
		(28 "In13.Cu" signal "IN5")
		(30 "In14.Cu" signal "GND6")
		(32 "In15.Cu" signal "IN6")
		(34 "In16.Cu" signal "GND7")
		(2 "B.Cu" signal "BOTTOM")
		(9 "F.Adhes" user "F.Adhesive")
		(11 "B.Adhes" user "B.Adhesive")
		(13 "F.Paste" user "Package Geometry/Pastemask Top")
		(15 "B.Paste" user "Package Geometry/Pastemask Bottom")
		(5 "F.SilkS" user "Ref Des/Silkscreen Top")
		(7 "B.SilkS" user "Ref Des/Silkscreen Bottom")
		(1 "F.Mask" user "Board Geometry/Soldermask Top")
		(3 "B.Mask" user "Board Geometry/Soldermask Bottom")
		(17 "Dwgs.User" user "User.Drawings")
		(19 "Cmts.User" user "User.Comments")
		(21 "Eco1.User" user "User.Eco1")
		(23 "Eco2.User" user "User.Eco2")
		(25 "Edge.Cuts" user "Board Geometry/Outline")
		(27 "Margin" user)
		(31 "F.CrtYd" user "Package Geometry/Place Bound Top")
		(29 "B.CrtYd" user "Package Geometry/Place Bound Bottom")
		(35 "F.Fab" user "Ref Des/Assembly Top")
		(33 "B.Fab" user "Ref Des/Assembly Bottom")
	)
	(footprint ""
		(layer "F.Cu")
		(at 369.2652 -407.67)
		(property "Reference" "Q153"
			(at -1.8288 -3.086608 0)
			(unlocked yes)
			(layer "F.SilkS")
			(effects
				(font
					(size 0.7874 0.5842)
					(thickness 0.1524)
				)
				(justify left)
			)
		)
		(property "Value" ""
			(at 0 0 0)
			(layer "F.Fab")
			(effects
				(font
					(size 1.27 1.27)
				)
			)
		)
		(duplicate_pad_numbers_are_jumpers no)
		(fp_line
			(start -1.332738 -1.100074)
			(end -0.4826 -1.100074)
			(stroke
				(width 0.1524)
				(type default)
			)
			(layer "F.SilkS")
		)
		(fp_line
			(start -1.332738 1.100074)
			(end -1.332738 -1.100074)
			(stroke
				(width 0.1524)
				(type default)
			)
			(layer "F.SilkS")
		)
		(fp_line
			(start -0.4826 -1.100074)
			(end 0 -0.541274)
			(stroke
				(width 0.1524)
				(type default)
			)
			(layer "F.SilkS")
		)
		(fp_line
			(start 0 -0.541274)
			(end 0.4826 -1.100074)
			(stroke
				(width 0.1524)
				(type default)
			)
			(layer "F.SilkS")
		)
		(fp_line
			(start 0.4826 -1.100074)
			(end 1.332738 -1.100074)
			(stroke
				(width 0.1524)
				(type default)
			)
			(layer "F.SilkS")
		)
		(fp_line
			(start 1.332738 -1.100074)
			(end 1.332738 1.100074)
			(stroke
				(width 0.1524)
				(type default)
			)
			(layer "F.SilkS")
		)
		(fp_line
			(start 1.332738 1.100074)
			(end -1.332738 1.100074)
			(stroke
				(width 0.1524)
				(type default)
			)
			(layer "F.SilkS")
		)
		(fp_poly
			(pts
				(xy -1.804924 -1.575816) (xy -1.308608 -2.072386) (xy -1.060196 -1.327658)
			)
			(stroke
				(width 0)
				(type default)
			)
			(fill yes)
			(layer "F.SilkS")
		)
		(fp_line
			(start -0.674878 -1.100074)
			(end 0.674878 -1.100074)
			(stroke
				(width 0.1)
				(type default)
			)
			(layer "F.Fab")
		)
		(fp_line
			(start -0.674878 1.100074)
			(end -0.674878 -1.100074)
			(stroke
				(width 0.1)
				(type default)
			)
			(layer "F.Fab")
		)
		(fp_line
			(start 0.674878 -1.100074)
			(end 0.674878 1.100074)
			(stroke
				(width 0.1)
				(type default)
			)
			(layer "F.Fab")
		)
		(fp_line
			(start 0.674878 1.100074)
			(end -0.674878 1.100074)
			(stroke
				(width 0.1)
				(type default)
			)
			(layer "F.Fab")
		)
		(fp_poly
			(pts
				(xy -2.2352 -0.298958) (xy -2.2352 -1.001014) (xy -1.533144 -0.649986)
			)
			(stroke
				(width 0)
				(type default)
			)
			(fill yes)
			(layer "F.Fab")
		)
		(pad "1" smd rect
			(at -0.94996 -0.649986 90)
			(size 0.4318 0.508)
			(layers "F.Cu" "F.Mask" "F.Paste")
			(net "GND")
		)
		(pad "2" smd rect
			(at -0.94996 0 90)
			(size 0.4318 0.508)
			(layers "F.Cu" "F.Mask" "F.Paste")
			(net "PRSNT_CABLE_SWB_B1_N")
		)
		(pad "3" smd rect
			(at -0.94996 0.649986 90)
			(size 0.4318 0.508)
			(layers "F.Cu" "F.Mask" "F.Paste")
			(net "PRSNT_CABLE_SWB_B1_ISO_N")
		)
		(pad "4" smd rect
			(at 0.94996 0.649986 90)
			(size 0.4318 0.508)
			(layers "F.Cu" "F.Mask" "F.Paste")
			(net "GND")
		)
		(pad "5" smd rect
			(at 0.94996 0 90)
			(size 0.4318 0.508)
			(layers "F.Cu" "F.Mask" "F.Paste")
			(net "PRSNT_CABLE_SWB_B1")
		)
		(pad "6" smd rect
			(at 0.94996 -0.649986 90)
			(size 0.4318 0.508)
			(layers "F.Cu" "F.Mask" "F.Paste")
			(net "PRSNT_CABLE_SWB_B1")
		)
	)
	(footprint ""
		(layer "F.Cu")
		(at 215.95588 -34.508948 180)
		(property "Reference" "R3592"
			(at 0 0 180)
			(layer "F.SilkS")
			(hide yes)
			(effects
				(font
					(size 1.27 1.27)
				)
			)
		)
		(property "Value" ""
			(at 0 0 180)
			(layer "F.Fab")
			(effects
				(font
					(size 1.27 1.27)
				)
			)
		)
		(duplicate_pad_numbers_are_jumpers no)
		(fp_line
			(start 0.7874 0.4064)
			(end -0.7874 0.4064)
			(stroke
				(width 0.1524)
				(type default)
			)
			(layer "F.SilkS")
		)
		(fp_line
			(start 0.7874 -0.4064)
			(end 0.7874 0.4064)
			(stroke
				(width 0.1524)
				(type default)
			)
			(layer "F.SilkS")
		)
		(fp_line
			(start -0.7874 0.4064)
			(end -0.7874 -0.4064)
			(stroke
				(width 0.1524)
				(type default)
			)
			(layer "F.SilkS")
		)
		(fp_line
			(start -0.7874 -0.4064)
			(end 0.7874 -0.4064)
			(stroke
				(width 0.1524)
				(type default)
			)
			(layer "F.SilkS")
		)
		(fp_line
			(start 0.67945 0.3048)
			(end 0.120396 0.3048)
			(stroke
				(width 0.1)
				(type default)
			)
			(layer "F.Fab")
		)
		(fp_line
			(start 0.67945 -0.3048)
			(end 0.67945 0.3048)
			(stroke
				(width 0.1)
				(type default)
			)
			(layer "F.Fab")
		)
		(fp_line
			(start 0.12065 -0.2794)
			(end 0.12065 -0.3048)
			(stroke
				(width 0.1)
				(type default)
			)
			(layer "F.Fab")
		)
		(fp_line
			(start 0.12065 -0.3048)
			(end 0.67945 -0.3048)
			(stroke
				(width 0.1)
				(type default)
			)
			(layer "F.Fab")
		)
		(fp_line
			(start 0.120396 0.3048)
			(end 0.120396 0.2794)
			(stroke
				(width 0.1)
				(type default)
			)
			(layer "F.Fab")
		)
		(fp_line
			(start 0.120396 0.2794)
			(end -0.12065 0.2794)
			(stroke
				(width 0.1)
				(type default)
			)
			(layer "F.Fab")
		)
		(fp_line
			(start -0.12065 0.3048)
			(end -0.67945 0.3048)
			(stroke
				(width 0.1)
				(type default)
			)
			(layer "F.Fab")
		)
		(fp_line
			(start -0.12065 0.2794)
			(end -0.12065 0.3048)
			(stroke
				(width 0.1)
				(type default)
			)
			(layer "F.Fab")
		)
		(fp_line
			(start -0.12065 -0.2794)
			(end 0.12065 -0.2794)
			(stroke
				(width 0.1)
				(type default)
			)
			(layer "F.Fab")
		)
		(fp_line
			(start -0.12065 -0.305054)
			(end -0.12065 -0.2794)
			(stroke
				(width 0.1)
				(type default)
			)
			(layer "F.Fab")
		)
		(fp_line
			(start -0.67945 0.3048)
			(end -0.67945 -0.305054)
			(stroke
				(width 0.1)
				(type default)
			)
			(layer "F.Fab")
		)
		(fp_line
			(start -0.67945 -0.305054)
			(end -0.12065 -0.305054)
			(stroke
				(width 0.1)
				(type default)
			)
			(layer "F.Fab")
		)
		(pad "1" smd circle
			(at -0.40005 0 180)
			(size 0 0)
			(layers "F.Cu" "F.Mask" "F.Paste")
			(net "SMB_INA230_3V3AUX_SCL")
		)
		(pad "2" smd circle
			(at 0.40005 0 180)
			(size 0 0)
			(layers "F.Cu" "F.Mask" "F.Paste")
			(net "SMB_INA230_5_3V3AUX_SCL_R")
		)
	)
)
